# BASEBOARD_FAB2 (Tioga Pass) — schematic netlist excerpt (pin names and nets, part order shuffled) for the footprints in the layout excerpt that follows; sources: Cadence DE-HDL packaged netlist, KiCad conversion of Wiwynn_Tioga_Pass_MB.brd

CF13  SC22P50V2JN-4GP  5%  pkg SMD-BCG  page 211 : \1\ = VR_PVCCIO_CPU0_AIREF1 ; \2\ = ISENSE_PVCCIO_CPU0_PH1_IMON
R1C3  RES  0.0 5% CHIP  pkg 0402  page 55 : A = SVID_CLK1_CPU1 ; B = SVID_CLK1_CPU1_R
R2T62  RES  0.0 5% EMPTY  pkg 0402  page 93 : A = H_CPU_ERR1_PCH_N ; B = FM_CPU_ERR1_LVT3_K_N

(kicad_pcb
	(version 20260206)
	(generator "pcbnew")
	(generator_version "10.0")
	(general
		(thickness 1.6)
		(legacy_teardrops no)
	)
	(paper "A4")
	(title_block
		(title "Wiwynn_Tioga_Pass_MB.brd")
		(comment 1 "Tioga Pass / footprints 3821-3823 of 4770")
	)
	(layers
		(0 "F.Cu" signal "TOP")
		(4 "In1.Cu" signal "L2GND")
		(6 "In2.Cu" signal "L3")
		(8 "In3.Cu" signal "L4GND")
		(10 "In4.Cu" signal "L5")
		(12 "In5.Cu" signal "L6GND")
		(14 "In6.Cu" signal "L7VCC")
		(16 "In7.Cu" signal "L8VCC")
		(18 "In8.Cu" signal "L9GND")
		(20 "In9.Cu" signal "L10")
		(22 "In10.Cu" signal "L11GND")
		(24 "In11.Cu" signal "L12")
		(26 "In12.Cu" signal "L13GND")
		(2 "B.Cu" signal "BOTTOM")
		(9 "F.Adhes" user "F.Adhesive")
		(11 "B.Adhes" user "B.Adhesive")
		(13 "F.Paste" user "Package Geometry/Pastemask Top")
		(15 "B.Paste" user "Package Geometry/Pastemask Bottom")
		(5 "F.SilkS" user "Ref Des/Silkscreen Top")
		(7 "B.SilkS" user "Ref Des/Silkscreen Bottom")
		(1 "F.Mask" user "Board Geometry/Soldermask Top")
		(3 "B.Mask" user "Board Geometry/Soldermask Bottom")
		(17 "Dwgs.User" user "User.Drawings")
		(19 "Cmts.User" user "User.Comments")
		(21 "Eco1.User" user "User.Eco1")
		(23 "Eco2.User" user "User.Eco2")
		(25 "Edge.Cuts" user "Board Geometry/Outline")
		(27 "Margin" user)
		(31 "F.CrtYd" user "Package Geometry/Place Bound Top")
		(29 "B.CrtYd" user "Package Geometry/Place Bound Bottom")
		(35 "F.Fab" user "Ref Des/Assembly Top")
		(33 "B.Fab" user "Ref Des/Assembly Bottom")
	)
	(footprint ""
		(layer "B.Cu")
		(at 39.307516 -106.085386 -90)
		(property "Reference" "R1C3"
			(at 0 0 90)
			(layer "B.SilkS")
			(hide yes)
			(effects
				(font
					(size 1.27 1.27)
				)
				(justify mirror)
			)
		)
		(property "Value" ""
			(at 0 0 90)
			(layer "B.Fab")
			(effects
				(font
					(size 1.27 1.27)
				)
				(justify mirror)
			)
		)
		(duplicate_pad_numbers_are_jumpers no)
		(fp_poly
			(pts
				(xy 0.2794 -0.1016) (xy -0.2794 -0.1016) (xy -0.2794 0.9906) (xy 0.2794 0.9906)
			)
			(stroke
				(width 0)
				(type default)
			)
			(fill no)
			(layer "B.CrtYd")
		)
		(fp_line
			(start -0.2794 0.9906)
			(end -0.2794 -0.1016)
			(stroke
				(width 0.1)
				(type default)
			)
			(layer "B.Fab")
		)
		(fp_line
			(start 0.2794 0.9906)
			(end -0.2794 0.9906)
			(stroke
				(width 0.1)
				(type default)
			)
			(layer "B.Fab")
		)
		(fp_line
			(start -0.2794 -0.1016)
			(end 0.2794 -0.1016)
			(stroke
				(width 0.1)
				(type default)
			)
			(layer "B.Fab")
		)
		(fp_line
			(start 0.2794 -0.1016)
			(end 0.2794 0.9906)
			(stroke
				(width 0.1)
				(type default)
			)
			(layer "B.Fab")
		)
		(pad "1" smd rect
			(at 0 0 90)
			(size 0.508 0.508)
			(layers "B.Cu" "B.Mask" "B.Paste")
			(net "SVID_CLK1_CPU1")
		)
		(pad "2" smd rect
			(at 0 0.889 90)
			(size 0.508 0.508)
			(layers "B.Cu" "B.Mask" "B.Paste")
			(net "SVID_CLK1_CPU1_R")
		)
		(zone
			(layer "B.Cu")
			(hatch none 0.5)
			(connect_pads
				(clearance 0)
			)
			(min_thickness 0.25)
			(keepout
				(tracks not_allowed)
				(vias allowed)
				(pads allowed)
				(copperpour not_allowed)
				(footprints allowed)
			)
			(placement
				(enabled no)
				(sheetname "")
			)
			(fill
				(thermal_gap 0.5)
				(thermal_bridge_width 0.5)
				(island_removal_mode 0)
			)
			(polygon
				(pts
					(xy 38.672516 -105.831386) (xy 38.672516 -106.339386) (xy 39.053516 -106.339386) (xy 39.053516 -105.831386)
				)
			)
		)
		(zone
			(layer "B.Cu")
			(hatch none 0.5)
			(connect_pads
				(clearance 0)
			)
			(min_thickness 0.25)
			(keepout
				(tracks allowed)
				(vias not_allowed)
				(pads allowed)
				(copperpour not_allowed)
				(footprints allowed)
			)
			(placement
				(enabled no)
				(sheetname "")
			)
			(fill
				(thermal_gap 0.5)
				(thermal_bridge_width 0.5)
				(island_removal_mode 0)
			)
			(polygon
				(pts
					(xy 39.053516 -105.831386) (xy 39.053516 -106.339386) (xy 38.672516 -106.339386) (xy 38.672516 -105.831386)
				)
			)
		)
	)
	(footprint ""
		(layer "B.Cu")
		(at 360.555794 -43.956986 90)
		(property "Reference" "R2T62"
			(at 0 0 90)
			(layer "B.SilkS")
			(hide yes)
			(effects
				(font
					(size 1.27 1.27)
				)
				(justify mirror)
			)
		)
		(property "Value" ""
			(at 0 0 90)
			(layer "B.Fab")
			(effects
				(font
					(size 1.27 1.27)
				)
				(justify mirror)
			)
		)
		(duplicate_pad_numbers_are_jumpers no)
		(fp_poly
			(pts
				(xy 0.2794 -0.1016) (xy -0.2794 -0.1016) (xy -0.2794 0.9906) (xy 0.2794 0.9906)
			)
			(stroke
				(width 0)
				(type default)
			)
			(fill no)
			(layer "B.CrtYd")
		)
		(fp_line
			(start 0.2794 -0.1016)
			(end 0.2794 0.9906)
			(stroke
				(width 0.1)
				(type default)
			)
			(layer "B.Fab")
		)
		(fp_line
			(start -0.2794 -0.1016)
			(end 0.2794 -0.1016)
			(stroke
				(width 0.1)
				(type default)
			)
			(layer "B.Fab")
		)
		(fp_line
			(start 0.2794 0.9906)
			(end -0.2794 0.9906)
			(stroke
				(width 0.1)
				(type default)
			)
			(layer "B.Fab")
		)
		(fp_line
			(start -0.2794 0.9906)
			(end -0.2794 -0.1016)
			(stroke
				(width 0.1)
				(type default)
			)
			(layer "B.Fab")
		)
		(pad "1" smd rect
			(at 0 0 270)
			(size 0.508 0.508)
			(layers "B.Cu" "B.Mask" "B.Paste")
			(net "H_CPU_ERR1_PCH_N")
		)
		(pad "2" smd rect
			(at 0 0.889 270)
			(size 0.508 0.508)
			(layers "B.Cu" "B.Mask" "B.Paste")
			(net "FM_CPU_ERR1_LVT3_K_N")
		)
		(zone
			(layer "B.Cu")
			(hatch none 0.5)
			(connect_pads
				(clearance 0)
			)
			(min_thickness 0.25)
			(keepout
				(tracks allowed)
				(vias not_allowed)
				(pads allowed)
				(copperpour not_allowed)
				(footprints allowed)
			)
			(placement
				(enabled no)
				(sheetname "")
			)
			(fill
				(thermal_gap 0.5)
				(thermal_bridge_width 0.5)
				(island_removal_mode 0)
			)
			(polygon
				(pts
					(xy 360.809794 -44.210986) (xy 360.809794 -43.702986) (xy 361.190794 -43.702986) (xy 361.190794 -44.210986)
				)
			)
		)
		(zone
			(layer "B.Cu")
			(hatch none 0.5)
			(connect_pads
				(clearance 0)
			)
			(min_thickness 0.25)
			(keepout
				(tracks not_allowed)
				(vias allowed)
				(pads allowed)
				(copperpour not_allowed)
				(footprints allowed)
			)
			(placement
				(enabled no)
				(sheetname "")
			)
			(fill
				(thermal_gap 0.5)
				(thermal_bridge_width 0.5)
				(island_removal_mode 0)
			)
			(polygon
				(pts
					(xy 361.190794 -44.210986) (xy 361.190794 -43.702986) (xy 360.809794 -43.702986) (xy 360.809794 -44.210986)
				)
			)
		)
	)
	(footprint ""
		(layer "B.Cu")
		(at 343.066878 -91.46413 -90)
		(property "Reference" "CF13"
			(at 0 0 90)
			(layer "B.SilkS")
			(hide yes)
			(effects
				(font
					(size 1.27 1.27)
				)
				(justify mirror)
			)
		)
		(property "Value" "*"
			(at -1.1811 -2.8194 270)
			(unlocked yes)
			(layer "B.Fab")
			(hide yes)
			(effects
				(font
					(size 1.27 1.016)
					(thickness 0.1524)
				)
				(justify mirror)
			)
		)
		(property "Device Type" "SC22P50V2JN-4GP_SMD-BCG-SC22P5A"
			(at -1.1811 -4.3434 270)
			(unlocked yes)
			(layer "B.Fab")
			(hide yes)
			(effects
				(font
					(size 1.27 1.016)
					(thickness 0.1524)
				)
				(justify mirror)
			)
		)
		(duplicate_pad_numbers_are_jumpers no)
		(fp_rect
			(start 0.4318 0.9525)
			(end -0.4318 -0.9525)
			(stroke
				(width 0)
				(type default)
			)
			(fill no)
			(layer "B.CrtYd")
		)
		(fp_rect
			(start 0.4318 0.9525)
			(end -0.4318 -0.9525)
			(stroke
				(width 0)
				(type default)
			)
			(fill no)
			(layer "B.Fab")
		)
		(pad "1" smd custom
			(at 0 -0.4445 90)
			(size 0.1524 0.1524)
			(layers "B.Cu" "B.Mask" "B.Paste")
			(net "VR_PVCCIO_CPU0_AIREF1")
			(options
				(clearance outline)
				(anchor circle)
			)
			(primitives
				(gr_poly
					(pts
						(arc
							(start 0.3048 0.2032)
							(mid 0.275042 0.275042)
							(end 0.2032 0.3048)
						)
						(arc
							(start -0.2032 0.3048)
							(mid -0.275042 0.275042)
							(end -0.3048 0.2032)
						)
						(arc
							(start -0.3048 -0.2032)
							(mid -0.275042 -0.275042)
							(end -0.2032 -0.3048)
						)
						(arc
							(start 0.2032 -0.3048)
							(mid 0.275042 -0.275042)
							(end 0.3048 -0.2032)
						)
					)
					(width 0)
					(fill yes)
				)
			)
		)
		(pad "2" smd custom
			(at 0 0.4445 90)
			(size 0.1524 0.1524)
			(layers "B.Cu" "B.Mask" "B.Paste")
			(net "ISENSE_PVCCIO_CPU0_PH1_IMON")
			(options
				(clearance outline)
				(anchor circle)
			)
			(primitives
				(gr_poly
					(pts
						(arc
							(start 0.3048 0.2032)
							(mid 0.275042 0.275042)
							(end 0.2032 0.3048)
						)
						(arc
							(start -0.2032 0.3048)
							(mid -0.275042 0.275042)
							(end -0.3048 0.2032)
						)
						(arc
							(start -0.3048 -0.2032)
							(mid -0.275042 -0.275042)
							(end -0.2032 -0.3048)
						)
						(arc
							(start 0.2032 -0.3048)
							(mid 0.275042 -0.275042)
							(end 0.3048 -0.2032)
						)
					)
					(width 0)
					(fill yes)
				)
			)
		)
	)
)
